# T6G (Grand Teton) — schematic netlist excerpt (pin names and nets, part order shuffled) for the footprints in the layout excerpt that follows; sources: Cadence DE-HDL packaged netlist, KiCad conversion of 04192023_DAF0TMB3IC0_F0TG_MB_C_brd_V02_OCP.brd

C402  Q_CAP  22UF 4V 20% X6S  pkg C0402  page 345 : A = P0V9_CPU1_RT2_2A ; B = GND
R531  Q_RES  2.2K 5% CHIP  pkg 0402LF  page 54 : A = CPU1_BP0 ; B = PVDD18_S5_P1
C570  Q_CAP  1UF 4V 20% X6S  pkg 0201  page 279 : A = P0V9_CPU0_RT0_2A ; B = GND

(kicad_pcb
	(version 20260206)
	(generator "pcbnew")
	(generator_version "10.0")
	(general
		(thickness 1.6)
		(legacy_teardrops no)
	)
	(paper "A4")
	(title_block
		(title "04192023_DAF0TMB3IC0_F0TG_MB_C_brd_V02_OCP.brd")
		(comment 1 "Grand Teton / footprints 7889-7891 of 8354")
	)
	(layers
		(0 "F.Cu" signal "TOP")
		(4 "In1.Cu" signal "GND")
		(6 "In2.Cu" signal "IN1")
		(8 "In3.Cu" signal "GND1")
		(10 "In4.Cu" signal "IN2")
		(12 "In5.Cu" signal "GND2")
		(14 "In6.Cu" signal "IN3")
		(16 "In7.Cu" signal "GND3")
		(18 "In8.Cu" signal "VCC")
		(20 "In9.Cu" signal "VCC1")
		(22 "In10.Cu" signal "GND4")
		(24 "In11.Cu" signal "IN4")
		(26 "In12.Cu" signal "GND5")
		(28 "In13.Cu" signal "IN5")
		(30 "In14.Cu" signal "GND6")
		(32 "In15.Cu" signal "IN6")
		(34 "In16.Cu" signal "GND7")
		(2 "B.Cu" signal "BOTTOM")
		(9 "F.Adhes" user "F.Adhesive")
		(11 "B.Adhes" user "B.Adhesive")
		(13 "F.Paste" user "Package Geometry/Pastemask Top")
		(15 "B.Paste" user "Package Geometry/Pastemask Bottom")
		(5 "F.SilkS" user "Ref Des/Silkscreen Top")
		(7 "B.SilkS" user "Ref Des/Silkscreen Bottom")
		(1 "F.Mask" user "Board Geometry/Soldermask Top")
		(3 "B.Mask" user "Board Geometry/Soldermask Bottom")
		(17 "Dwgs.User" user "User.Drawings")
		(19 "Cmts.User" user "User.Comments")
		(21 "Eco1.User" user "User.Eco1")
		(23 "Eco2.User" user "User.Eco2")
		(25 "Edge.Cuts" user "Board Geometry/Outline")
		(27 "Margin" user)
		(31 "F.CrtYd" user "Package Geometry/Place Bound Top")
		(29 "B.CrtYd" user "Package Geometry/Place Bound Bottom")
		(35 "F.Fab" user "Ref Des/Assembly Top")
		(33 "B.Fab" user "Ref Des/Assembly Bottom")
	)
	(footprint ""
		(layer "B.Cu")
		(at 95.837502 -205.14945 90)
		(property "Reference" "R531"
			(at 0 0 90)
			(layer "B.SilkS")
			(hide yes)
			(effects
				(font
					(size 1.27 1.27)
				)
				(justify mirror)
			)
		)
		(property "Value" ""
			(at 0 0 90)
			(layer "B.Fab")
			(effects
				(font
					(size 1.27 1.27)
				)
				(justify mirror)
			)
		)
		(duplicate_pad_numbers_are_jumpers no)
		(fp_line
			(start 0.7874 -0.4064)
			(end -0.7874 -0.4064)
			(stroke
				(width 0.1524)
				(type default)
			)
			(layer "B.SilkS")
		)
		(fp_line
			(start -0.7874 -0.4064)
			(end -0.7874 0.4064)
			(stroke
				(width 0.1524)
				(type default)
			)
			(layer "B.SilkS")
		)
		(fp_line
			(start 0.7874 0.4064)
			(end 0.7874 -0.4064)
			(stroke
				(width 0.1524)
				(type default)
			)
			(layer "B.SilkS")
		)
		(fp_line
			(start -0.7874 0.4064)
			(end 0.7874 0.4064)
			(stroke
				(width 0.1524)
				(type default)
			)
			(layer "B.SilkS")
		)
		(fp_line
			(start 0.67945 -0.305054)
			(end 0.12065 -0.305054)
			(stroke
				(width 0.1)
				(type default)
			)
			(layer "B.Fab")
		)
		(fp_line
			(start 0.12065 -0.305054)
			(end 0.12065 -0.2794)
			(stroke
				(width 0.1)
				(type default)
			)
			(layer "B.Fab")
		)
		(fp_line
			(start -0.12065 -0.3048)
			(end -0.67945 -0.3048)
			(stroke
				(width 0.1)
				(type default)
			)
			(layer "B.Fab")
		)
		(fp_line
			(start -0.67945 -0.3048)
			(end -0.67945 0.3048)
			(stroke
				(width 0.1)
				(type default)
			)
			(layer "B.Fab")
		)
		(fp_line
			(start 0.12065 -0.2794)
			(end -0.12065 -0.2794)
			(stroke
				(width 0.1)
				(type default)
			)
			(layer "B.Fab")
		)
		(fp_line
			(start -0.12065 -0.2794)
			(end -0.12065 -0.3048)
			(stroke
				(width 0.1)
				(type default)
			)
			(layer "B.Fab")
		)
		(fp_line
			(start 0.12065 0.2794)
			(end 0.12065 0.3048)
			(stroke
				(width 0.1)
				(type default)
			)
			(layer "B.Fab")
		)
		(fp_line
			(start -0.120396 0.2794)
			(end 0.12065 0.2794)
			(stroke
				(width 0.1)
				(type default)
			)
			(layer "B.Fab")
		)
		(fp_line
			(start 0.67945 0.3048)
			(end 0.67945 -0.305054)
			(stroke
				(width 0.1)
				(type default)
			)
			(layer "B.Fab")
		)
		(fp_line
			(start 0.12065 0.3048)
			(end 0.67945 0.3048)
			(stroke
				(width 0.1)
				(type default)
			)
			(layer "B.Fab")
		)
		(fp_line
			(start -0.120396 0.3048)
			(end -0.120396 0.2794)
			(stroke
				(width 0.1)
				(type default)
			)
			(layer "B.Fab")
		)
		(fp_line
			(start -0.67945 0.3048)
			(end -0.120396 0.3048)
			(stroke
				(width 0.1)
				(type default)
			)
			(layer "B.Fab")
		)
		(pad "1" smd circle
			(at 0.40005 0 270)
			(size 0 0)
			(layers "B.Cu" "B.Mask" "B.Paste")
			(net "CPU1_BP0")
		)
		(pad "2" smd circle
			(at -0.40005 0 270)
			(size 0 0)
			(layers "B.Cu" "B.Mask" "B.Paste")
			(net "PVDD18_S5_P1")
		)
	)
	(footprint ""
		(layer "B.Cu")
		(at 318.97828 -395.148562 90)
		(property "Reference" "C570"
			(at 0 0 90)
			(layer "B.SilkS")
			(hide yes)
			(effects
				(font
					(size 1.27 1.27)
				)
				(justify mirror)
			)
		)
		(property "Value" ""
			(at 0 0 90)
			(layer "B.Fab")
			(effects
				(font
					(size 1.27 1.27)
				)
				(justify mirror)
			)
		)
		(duplicate_pad_numbers_are_jumpers no)
		(fp_line
			(start 0.299974 -0.150114)
			(end -0.299974 -0.150114)
			(stroke
				(width 0.1)
				(type default)
			)
			(layer "B.Fab")
		)
		(fp_line
			(start -0.299974 -0.150114)
			(end -0.299974 0.150114)
			(stroke
				(width 0.1)
				(type default)
			)
			(layer "B.Fab")
		)
		(fp_line
			(start 0.299974 0.150114)
			(end 0.299974 -0.150114)
			(stroke
				(width 0.1)
				(type default)
			)
			(layer "B.Fab")
		)
		(fp_line
			(start -0.299974 0.150114)
			(end 0.299974 0.150114)
			(stroke
				(width 0.1)
				(type default)
			)
			(layer "B.Fab")
		)
		(pad "1" smd rect
			(at 0.2667 0 270)
			(size 0.3048 0.381)
			(layers "B.Cu" "B.Mask" "B.Paste")
			(net "P0V9_CPU0_RT0_2A")
		)
		(pad "2" smd rect
			(at -0.2667 0 270)
			(size 0.3048 0.381)
			(layers "B.Cu" "B.Mask" "B.Paste")
			(net "GND")
		)
	)
	(footprint ""
		(layer "B.Cu")
		(at 166.373048 -390.560052 90)
		(property "Reference" "C402"
			(at 0 0 90)
			(layer "B.SilkS")
			(hide yes)
			(effects
				(font
					(size 1.27 1.27)
				)
				(justify mirror)
			)
		)
		(property "Value" ""
			(at 0 0 90)
			(layer "B.Fab")
			(effects
				(font
					(size 1.27 1.27)
				)
				(justify mirror)
			)
		)
		(duplicate_pad_numbers_are_jumpers no)
		(fp_line
			(start 0.7874 -0.4064)
			(end -0.7874 -0.4064)
			(stroke
				(width 0.1524)
				(type default)
			)
			(layer "B.SilkS")
		)
		(fp_line
			(start -0.7874 -0.4064)
			(end -0.7874 0.4064)
			(stroke
				(width 0.1524)
				(type default)
			)
			(layer "B.SilkS")
		)
		(fp_line
			(start 0.7874 0.4064)
			(end 0.7874 -0.4064)
			(stroke
				(width 0.1524)
				(type default)
			)
			(layer "B.SilkS")
		)
		(fp_line
			(start -0.7874 0.4064)
			(end 0.7874 0.4064)
			(stroke
				(width 0.1524)
				(type default)
			)
			(layer "B.SilkS")
		)
		(fp_line
			(start 0.67945 -0.305054)
			(end 0.12065 -0.305054)
			(stroke
				(width 0.1)
				(type default)
			)
			(layer "B.Fab")
		)
		(fp_line
			(start 0.12065 -0.305054)
			(end 0.12065 -0.2794)
			(stroke
				(width 0.1)
				(type default)
			)
			(layer "B.Fab")
		)
		(fp_line
			(start -0.12065 -0.3048)
			(end -0.67945 -0.3048)
			(stroke
				(width 0.1)
				(type default)
			)
			(layer "B.Fab")
		)
		(fp_line
			(start -0.67945 -0.3048)
			(end -0.67945 0.3048)
			(stroke
				(width 0.1)
				(type default)
			)
			(layer "B.Fab")
		)
		(fp_line
			(start 0.12065 -0.2794)
			(end -0.12065 -0.2794)
			(stroke
				(width 0.1)
				(type default)
			)
			(layer "B.Fab")
		)
		(fp_line
			(start -0.12065 -0.2794)
			(end -0.12065 -0.3048)
			(stroke
				(width 0.1)
				(type default)
			)
			(layer "B.Fab")
		)
		(fp_line
			(start 0.12065 0.2794)
			(end 0.12065 0.3048)
			(stroke
				(width 0.1)
				(type default)
			)
			(layer "B.Fab")
		)
		(fp_line
			(start -0.120396 0.2794)
			(end 0.12065 0.2794)
			(stroke
				(width 0.1)
				(type default)
			)
			(layer "B.Fab")
		)
		(fp_line
			(start 0.67945 0.3048)
			(end 0.67945 -0.305054)
			(stroke
				(width 0.1)
				(type default)
			)
			(layer "B.Fab")
		)
		(fp_line
			(start 0.12065 0.3048)
			(end 0.67945 0.3048)
			(stroke
				(width 0.1)
				(type default)
			)
			(layer "B.Fab")
		)
		(fp_line
			(start -0.120396 0.3048)
			(end -0.120396 0.2794)
			(stroke
				(width 0.1)
				(type default)
			)
			(layer "B.Fab")
		)
		(fp_line
			(start -0.67945 0.3048)
			(end -0.120396 0.3048)
			(stroke
				(width 0.1)
				(type default)
			)
			(layer "B.Fab")
		)
		(pad "1" smd circle
			(at 0.40005 0 270)
			(size 0 0)
			(layers "B.Cu" "B.Mask" "B.Paste")
			(net "P0V9_CPU1_RT2_2A")
		)
		(pad "2" smd circle
			(at -0.40005 0 270)
			(size 0 0)
			(layers "B.Cu" "B.Mask" "B.Paste")
			(net "GND")
		)
	)
)
